A
A
B
B
C
C
D
D
E
E
1
1
2
2
3
3
4
4
AN4
AN3
AN2
AN1
S3
JP2
JP1
U13
U11
U8
S4
S2
S1
P2
P1
U7
R36
R37
R38
R39
R40
R41
R24
R23
R26
R25
R42
R43
R33
R32
R27
R7
R6
R5
R35
R34
R31
R30
R29
R28
R1
R22
R21
R20
R19
R18
R9
R8
R4
R3
R2
C77
C78
C79
C80
C81
C82
C83
C66
C63
C61
C59
C57
C18
C17
C16
C15
C12
C11
C10
C9
C2
D14
D13
D12
D11
D10
D9
D4
C22
C20
F1
FB3
FB2
FB1
U12
C76
C68
C67
C64
C4
C3
C85
C86
C92
C55
C21
C19
D8
D7
D6
D5
AN8
AN7
AN6
AN5
D3
D2
D1
C72
C73
C74
C75
C71
C70
C84
C69
C65
C62
C60
C58
C56
C14
C13
C8
C7
C6
C5
C1
C91
C54
S6
S5
U2
U1
U16
U6
U10
X1
D18
D17
D16
D15
J4
L2
L1
U9
J3
U5
AN4
AN3
AN2
AN1
J1
J2
SW1
View from Top side (Scale 1:1)
188.10mm
106.32mm
10.17mm
20.18mm
Gold finger edge
